# T6G (Grand Teton) — schematic netlist excerpt (pin names and nets, part order shuffled) for the footprints in the layout excerpt that follows; sources: Cadence DE-HDL packaged netlist, KiCad conversion of 04192023_DAF0TMB3IC0_F0TG_MB_C_brd_V02_OCP.brd

PR6631  Q_RES  0 5% CHIP  pkg 0402LF  page 365 : A = P0V9_RETIMER_CPU1_VOS2 ; B = P0V9_CPU1_RT_2D
R617  Q_RES  4.7K 5% CHIP  pkg 0402LF  page 172 : A = PVDD18_S5_P0 ; B = JTAG_BMC_R_D_OE

(kicad_pcb
	(version 20260206)
	(generator "pcbnew")
	(generator_version "10.0")
	(general
		(thickness 1.6)
		(legacy_teardrops no)
	)
	(paper "A4")
	(title_block
		(title "04192023_DAF0TMB3IC0_F0TG_MB_C_brd_V02_OCP.brd")
		(comment 1 "Grand Teton / footprints 1457-1458 of 8354")
	)
	(layers
		(0 "F.Cu" signal "TOP")
		(4 "In1.Cu" signal "GND")
		(6 "In2.Cu" signal "IN1")
		(8 "In3.Cu" signal "GND1")
		(10 "In4.Cu" signal "IN2")
		(12 "In5.Cu" signal "GND2")
		(14 "In6.Cu" signal "IN3")
		(16 "In7.Cu" signal "GND3")
		(18 "In8.Cu" signal "VCC")
		(20 "In9.Cu" signal "VCC1")
		(22 "In10.Cu" signal "GND4")
		(24 "In11.Cu" signal "IN4")
		(26 "In12.Cu" signal "GND5")
		(28 "In13.Cu" signal "IN5")
		(30 "In14.Cu" signal "GND6")
		(32 "In15.Cu" signal "IN6")
		(34 "In16.Cu" signal "GND7")
		(2 "B.Cu" signal "BOTTOM")
		(9 "F.Adhes" user "F.Adhesive")
		(11 "B.Adhes" user "B.Adhesive")
		(13 "F.Paste" user "Package Geometry/Pastemask Top")
		(15 "B.Paste" user "Package Geometry/Pastemask Bottom")
		(5 "F.SilkS" user "Ref Des/Silkscreen Top")
		(7 "B.SilkS" user "Ref Des/Silkscreen Bottom")
		(1 "F.Mask" user "Board Geometry/Soldermask Top")
		(3 "B.Mask" user "Board Geometry/Soldermask Bottom")
		(17 "Dwgs.User" user "User.Drawings")
		(19 "Cmts.User" user "User.Comments")
		(21 "Eco1.User" user "User.Eco1")
		(23 "Eco2.User" user "User.Eco2")
		(25 "Edge.Cuts" user "Board Geometry/Outline")
		(27 "Margin" user)
		(31 "F.CrtYd" user "Package Geometry/Place Bound Top")
		(29 "B.CrtYd" user "Package Geometry/Place Bound Bottom")
		(35 "F.Fab" user "Ref Des/Assembly Top")
		(33 "B.Fab" user "Ref Des/Assembly Bottom")
	)
	(footprint ""
		(layer "F.Cu")
		(at 21.512784 -392.396726 180)
		(property "Reference" "PR6631"
			(at 0 0 180)
			(layer "F.SilkS")
			(hide yes)
			(effects
				(font
					(size 1.27 1.27)
				)
			)
		)
		(property "Value" ""
			(at 0 0 180)
			(layer "F.Fab")
			(effects
				(font
					(size 1.27 1.27)
				)
			)
		)
		(duplicate_pad_numbers_are_jumpers no)
		(fp_line
			(start 0.7874 0.4064)
			(end -0.7874 0.4064)
			(stroke
				(width 0.1524)
				(type default)
			)
			(layer "F.SilkS")
		)
		(fp_line
			(start 0.7874 -0.4064)
			(end 0.7874 0.4064)
			(stroke
				(width 0.1524)
				(type default)
			)
			(layer "F.SilkS")
		)
		(fp_line
			(start -0.356616 -0.4064)
			(end 0.7874 -0.4064)
			(stroke
				(width 0.1524)
				(type default)
			)
			(layer "F.SilkS")
		)
		(fp_line
			(start -0.7874 0.4064)
			(end -0.7874 0.033274)
			(stroke
				(width 0.1524)
				(type default)
			)
			(layer "F.SilkS")
		)
		(fp_line
			(start 0.67945 0.3048)
			(end 0.120396 0.3048)
			(stroke
				(width 0.1)
				(type default)
			)
			(layer "F.Fab")
		)
		(fp_line
			(start 0.67945 -0.3048)
			(end 0.67945 0.3048)
			(stroke
				(width 0.1)
				(type default)
			)
			(layer "F.Fab")
		)
		(fp_line
			(start 0.12065 -0.2794)
			(end 0.12065 -0.3048)
			(stroke
				(width 0.1)
				(type default)
			)
			(layer "F.Fab")
		)
		(fp_line
			(start 0.12065 -0.3048)
			(end 0.67945 -0.3048)
			(stroke
				(width 0.1)
				(type default)
			)
			(layer "F.Fab")
		)
		(fp_line
			(start 0.120396 0.3048)
			(end 0.120396 0.2794)
			(stroke
				(width 0.1)
				(type default)
			)
			(layer "F.Fab")
		)
		(fp_line
			(start 0.120396 0.2794)
			(end -0.12065 0.2794)
			(stroke
				(width 0.1)
				(type default)
			)
			(layer "F.Fab")
		)
		(fp_line
			(start -0.12065 0.3048)
			(end -0.67945 0.3048)
			(stroke
				(width 0.1)
				(type default)
			)
			(layer "F.Fab")
		)
		(fp_line
			(start -0.12065 0.2794)
			(end -0.12065 0.3048)
			(stroke
				(width 0.1)
				(type default)
			)
			(layer "F.Fab")
		)
		(fp_line
			(start -0.12065 -0.2794)
			(end 0.12065 -0.2794)
			(stroke
				(width 0.1)
				(type default)
			)
			(layer "F.Fab")
		)
		(fp_line
			(start -0.12065 -0.305054)
			(end -0.12065 -0.2794)
			(stroke
				(width 0.1)
				(type default)
			)
			(layer "F.Fab")
		)
		(fp_line
			(start -0.67945 0.3048)
			(end -0.67945 -0.305054)
			(stroke
				(width 0.1)
				(type default)
			)
			(layer "F.Fab")
		)
		(fp_line
			(start -0.67945 -0.305054)
			(end -0.12065 -0.305054)
			(stroke
				(width 0.1)
				(type default)
			)
			(layer "F.Fab")
		)
		(pad "1" smd circle
			(at -0.40005 0 180)
			(size 0 0)
			(layers "F.Cu" "F.Mask" "F.Paste")
			(net "P0V9_RETIMER_CPU1_VOS2")
		)
		(pad "2" smd circle
			(at 0.40005 0 180)
			(size 0 0)
			(layers "F.Cu" "F.Mask" "F.Paste")
			(net "P0V9_CPU1_RT_2D")
		)
	)
	(footprint ""
		(layer "F.Cu")
		(at 123.127262 -52.534058)
		(property "Reference" "R617"
			(at 0 0 0)
			(layer "F.SilkS")
			(hide yes)
			(effects
				(font
					(size 1.27 1.27)
				)
			)
		)
		(property "Value" ""
			(at 0 0 0)
			(layer "F.Fab")
			(effects
				(font
					(size 1.27 1.27)
				)
			)
		)
		(duplicate_pad_numbers_are_jumpers no)
		(fp_line
			(start -0.7874 -0.4064)
			(end -0.623062 -0.4064)
			(stroke
				(width 0.1524)
				(type default)
			)
			(layer "F.SilkS")
		)
		(fp_line
			(start -0.7874 0.4064)
			(end -0.7874 -0.4064)
			(stroke
				(width 0.1524)
				(type default)
			)
			(layer "F.SilkS")
		)
		(fp_line
			(start 0.189738 -0.4064)
			(end 0.7874 -0.4064)
			(stroke
				(width 0.1524)
				(type default)
			)
			(layer "F.SilkS")
		)
		(fp_line
			(start 0.7874 -0.4064)
			(end 0.7874 0.4064)
			(stroke
				(width 0.1524)
				(type default)
			)
			(layer "F.SilkS")
		)
		(fp_line
			(start 0.7874 0.4064)
			(end -0.7874 0.4064)
			(stroke
				(width 0.1524)
				(type default)
			)
			(layer "F.SilkS")
		)
		(fp_line
			(start -0.67945 -0.305054)
			(end -0.12065 -0.305054)
			(stroke
				(width 0.1)
				(type default)
			)
			(layer "F.Fab")
		)
		(fp_line
			(start -0.67945 0.3048)
			(end -0.67945 -0.305054)
			(stroke
				(width 0.1)
				(type default)
			)
			(layer "F.Fab")
		)
		(fp_line
			(start -0.12065 -0.305054)
			(end -0.12065 -0.2794)
			(stroke
				(width 0.1)
				(type default)
			)
			(layer "F.Fab")
		)
		(fp_line
			(start -0.12065 -0.2794)
			(end 0.12065 -0.2794)
			(stroke
				(width 0.1)
				(type default)
			)
			(layer "F.Fab")
		)
		(fp_line
			(start -0.12065 0.2794)
			(end -0.12065 0.3048)
			(stroke
				(width 0.1)
				(type default)
			)
			(layer "F.Fab")
		)
		(fp_line
			(start -0.12065 0.3048)
			(end -0.67945 0.3048)
			(stroke
				(width 0.1)
				(type default)
			)
			(layer "F.Fab")
		)
		(fp_line
			(start 0.120396 0.2794)
			(end -0.12065 0.2794)
			(stroke
				(width 0.1)
				(type default)
			)
			(layer "F.Fab")
		)
		(fp_line
			(start 0.120396 0.3048)
			(end 0.120396 0.2794)
			(stroke
				(width 0.1)
				(type default)
			)
			(layer "F.Fab")
		)
		(fp_line
			(start 0.12065 -0.3048)
			(end 0.67945 -0.3048)
			(stroke
				(width 0.1)
				(type default)
			)
			(layer "F.Fab")
		)
		(fp_line
			(start 0.12065 -0.2794)
			(end 0.12065 -0.3048)
			(stroke
				(width 0.1)
				(type default)
			)
			(layer "F.Fab")
		)
		(fp_line
			(start 0.67945 -0.3048)
			(end 0.67945 0.3048)
			(stroke
				(width 0.1)
				(type default)
			)
			(layer "F.Fab")
		)
		(fp_line
			(start 0.67945 0.3048)
			(end 0.120396 0.3048)
			(stroke
				(width 0.1)
				(type default)
			)
			(layer "F.Fab")
		)
		(pad "1" smd circle
			(at -0.40005 0)
			(size 0 0)
			(layers "F.Cu" "F.Mask" "F.Paste")
			(net "PVDD18_S5_P0")
		)
		(pad "2" smd circle
			(at 0.40005 0)
			(size 0 0)
			(layers "F.Cu" "F.Mask" "F.Paste")
			(net "JTAG_BMC_R_D_OE")
		)
	)
)
